# BASEBOARD_FAB2 (Tioga Pass) — schematic netlist excerpt (pin names and nets, part order shuffled) for the footprints in the layout excerpt that follows; sources: Cadence DE-HDL packaged netlist, KiCad conversion of Wiwynn_Tioga_Pass_MB.brd

R6F8  RES  0.0 5% EMPTY  pkg 0402  page 104 : A = CLK_322M_156M_CPU0_OSC_VRM_DP ; B = CLK_156M_OSC_CPU0_HFI_DP
RT12  1R3F-GP  1%  pkg RCL_GP  page 208 : \1\ = VR_PVCCIN_CPU1_PHASE3_RC ; \2\ = GND
R7B13  RES  6.19K 1% CHIP  pkg 0402  page 232 : A = VR_FB_PVPP_DEF ; B = AGND_PVPP_DEF

(kicad_pcb
	(version 20260206)
	(generator "pcbnew")
	(generator_version "10.0")
	(general
		(thickness 1.6)
		(legacy_teardrops no)
	)
	(paper "A4")
	(title_block
		(title "Wiwynn_Tioga_Pass_MB.brd")
		(comment 1 "Tioga Pass / footprints 1289-1291 of 4770")
	)
	(layers
		(0 "F.Cu" signal "TOP")
		(4 "In1.Cu" signal "L2GND")
		(6 "In2.Cu" signal "L3")
		(8 "In3.Cu" signal "L4GND")
		(10 "In4.Cu" signal "L5")
		(12 "In5.Cu" signal "L6GND")
		(14 "In6.Cu" signal "L7VCC")
		(16 "In7.Cu" signal "L8VCC")
		(18 "In8.Cu" signal "L9GND")
		(20 "In9.Cu" signal "L10")
		(22 "In10.Cu" signal "L11GND")
		(24 "In11.Cu" signal "L12")
		(26 "In12.Cu" signal "L13GND")
		(2 "B.Cu" signal "BOTTOM")
		(9 "F.Adhes" user "F.Adhesive")
		(11 "B.Adhes" user "B.Adhesive")
		(13 "F.Paste" user "Package Geometry/Pastemask Top")
		(15 "B.Paste" user "Package Geometry/Pastemask Bottom")
		(5 "F.SilkS" user "Ref Des/Silkscreen Top")
		(7 "B.SilkS" user "Ref Des/Silkscreen Bottom")
		(1 "F.Mask" user "Board Geometry/Soldermask Top")
		(3 "B.Mask" user "Board Geometry/Soldermask Bottom")
		(17 "Dwgs.User" user "User.Drawings")
		(19 "Cmts.User" user "User.Comments")
		(21 "Eco1.User" user "User.Eco1")
		(23 "Eco2.User" user "User.Eco2")
		(25 "Edge.Cuts" user "Board Geometry/Outline")
		(27 "Margin" user)
		(31 "F.CrtYd" user "Package Geometry/Place Bound Top")
		(29 "B.CrtYd" user "Package Geometry/Place Bound Bottom")
		(35 "F.Fab" user "Ref Des/Assembly Top")
		(33 "B.Fab" user "Ref Des/Assembly Bottom")
	)
	(footprint ""
		(layer "F.Cu")
		(at 36.7538 -69.3166 -90)
		(property "Reference" "RT12"
			(at 0 0 270)
			(layer "F.SilkS")
			(hide yes)
			(effects
				(font
					(size 1.27 1.27)
				)
			)
		)
		(property "Value" "*"
			(at -0.0254 -2.6289 270)
			(unlocked yes)
			(layer "F.Fab")
			(hide yes)
			(effects
				(font
					(size 1.27 1.016)
					(thickness 0.1524)
				)
			)
		)
		(property "Device Type" "1R3F-GP_RCL_GP-1R3F-GP,64.1R00A"
			(at -0.0254 -4.1529 270)
			(unlocked yes)
			(layer "F.Fab")
			(hide yes)
			(effects
				(font
					(size 1.27 1.016)
					(thickness 0.1524)
				)
			)
		)
		(duplicate_pad_numbers_are_jumpers no)
		(fp_line
			(start -0.4826 0)
			(end -0.2032 0)
			(stroke
				(width 0.2032)
				(type default)
			)
			(layer "F.SilkS")
		)
		(fp_line
			(start 0.2032 0)
			(end 0.4826 0)
			(stroke
				(width 0.2032)
				(type default)
			)
			(layer "F.SilkS")
		)
		(fp_rect
			(start -0.5842 1.3335)
			(end 0.5842 -1.3335)
			(stroke
				(width 0)
				(type default)
			)
			(fill no)
			(layer "F.CrtYd")
		)
		(fp_rect
			(start -0.5842 1.3335)
			(end 0.5842 -1.3335)
			(stroke
				(width 0)
				(type default)
			)
			(fill no)
			(layer "F.Fab")
		)
		(pad "1" smd custom
			(at 0 -0.762 270)
			(size 0.2159 0.2159)
			(layers "F.Cu" "F.Mask" "F.Paste")
			(net "VR_PVCCIN_CPU1_PHASE3_RC")
			(options
				(clearance outline)
				(anchor circle)
			)
			(primitives
				(gr_poly
					(pts
						(arc
							(start -0.3302 -0.4318)
							(mid -0.402042 -0.402042)
							(end -0.4318 -0.3302)
						)
						(arc
							(start -0.4318 0.3302)
							(mid -0.402042 0.402042)
							(end -0.3302 0.4318)
						)
						(arc
							(start 0.3302 0.4318)
							(mid 0.402042 0.402042)
							(end 0.4318 0.3302)
						)
						(arc
							(start 0.4318 -0.3302)
							(mid 0.402042 -0.402042)
							(end 0.3302 -0.4318)
						)
					)
					(width 0)
					(fill yes)
				)
			)
		)
		(pad "2" smd custom
			(at 0 0.762 270)
			(size 0.2159 0.2159)
			(layers "F.Cu" "F.Mask" "F.Paste")
			(net "GND")
			(options
				(clearance outline)
				(anchor circle)
			)
			(primitives
				(gr_poly
					(pts
						(arc
							(start -0.3302 -0.4318)
							(mid -0.402042 -0.402042)
							(end -0.4318 -0.3302)
						)
						(arc
							(start -0.4318 0.3302)
							(mid -0.402042 0.402042)
							(end -0.3302 0.4318)
						)
						(arc
							(start 0.3302 0.4318)
							(mid 0.402042 0.402042)
							(end 0.4318 0.3302)
						)
						(arc
							(start 0.4318 -0.3302)
							(mid 0.402042 -0.402042)
							(end 0.3302 -0.4318)
						)
					)
					(width 0)
					(fill yes)
				)
			)
		)
	)
	(footprint ""
		(layer "F.Cu")
		(at 340.7664 -128.3335)
		(property "Reference" "R7B13"
			(at 0 0 0)
			(layer "F.SilkS")
			(hide yes)
			(effects
				(font
					(size 1.27 1.27)
				)
			)
		)
		(property "Value" ""
			(at 0 0 0)
			(layer "F.Fab")
			(effects
				(font
					(size 1.27 1.27)
				)
			)
		)
		(duplicate_pad_numbers_are_jumpers no)
		(fp_poly
			(pts
				(xy -0.2794 -0.1016) (xy 0.2794 -0.1016) (xy 0.2794 0.9906) (xy -0.2794 0.9906)
			)
			(stroke
				(width 0)
				(type default)
			)
			(fill no)
			(layer "F.CrtYd")
		)
		(fp_line
			(start -0.2794 -0.1016)
			(end -0.2794 0.9906)
			(stroke
				(width 0.1)
				(type default)
			)
			(layer "F.Fab")
		)
		(fp_line
			(start -0.2794 0.9906)
			(end 0.2794 0.9906)
			(stroke
				(width 0.1)
				(type default)
			)
			(layer "F.Fab")
		)
		(fp_line
			(start 0.2794 -0.1016)
			(end -0.2794 -0.1016)
			(stroke
				(width 0.1)
				(type default)
			)
			(layer "F.Fab")
		)
		(fp_line
			(start 0.2794 0.9906)
			(end 0.2794 -0.1016)
			(stroke
				(width 0.1)
				(type default)
			)
			(layer "F.Fab")
		)
		(pad "1" smd rect
			(at 0 0)
			(size 0.508 0.508)
			(layers "F.Cu" "F.Mask" "F.Paste")
			(net "VR_FB_PVPP_DEF")
		)
		(pad "2" smd rect
			(at 0 0.889)
			(size 0.508 0.508)
			(layers "F.Cu" "F.Mask" "F.Paste")
			(net "AGND_PVPP_DEF")
		)
		(zone
			(layer "F.Cu")
			(hatch none 0.5)
			(connect_pads
				(clearance 0)
			)
			(min_thickness 0.25)
			(keepout
				(tracks allowed)
				(vias not_allowed)
				(pads allowed)
				(copperpour not_allowed)
				(footprints allowed)
			)
			(placement
				(enabled no)
				(sheetname "")
			)
			(fill
				(thermal_gap 0.5)
				(thermal_bridge_width 0.5)
				(island_removal_mode 0)
			)
			(polygon
				(pts
					(xy 340.5124 -128.0795) (xy 341.0204 -128.0795) (xy 341.0204 -127.6985) (xy 340.5124 -127.6985)
				)
			)
		)
		(zone
			(layer "F.Cu")
			(hatch none 0.5)
			(connect_pads
				(clearance 0)
			)
			(min_thickness 0.25)
			(keepout
				(tracks not_allowed)
				(vias allowed)
				(pads allowed)
				(copperpour not_allowed)
				(footprints allowed)
			)
			(placement
				(enabled no)
				(sheetname "")
			)
			(fill
				(thermal_gap 0.5)
				(thermal_bridge_width 0.5)
				(island_removal_mode 0)
			)
			(polygon
				(pts
					(xy 340.5124 -127.6985) (xy 341.0204 -127.6985) (xy 341.0204 -128.0795) (xy 340.5124 -128.0795)
				)
			)
		)
	)
	(footprint ""
		(layer "F.Cu")
		(at 318.8716 -28.045918 180)
		(property "Reference" "R6F8"
			(at 0 0 180)
			(layer "F.SilkS")
			(hide yes)
			(effects
				(font
					(size 1.27 1.27)
				)
			)
		)
		(property "Value" ""
			(at 0 0 180)
			(layer "F.Fab")
			(effects
				(font
					(size 1.27 1.27)
				)
			)
		)
		(duplicate_pad_numbers_are_jumpers no)
		(fp_poly
			(pts
				(xy -0.2794 -0.1016) (xy 0.2794 -0.1016) (xy 0.2794 0.9906) (xy -0.2794 0.9906)
			)
			(stroke
				(width 0)
				(type default)
			)
			(fill no)
			(layer "F.CrtYd")
		)
		(fp_line
			(start 0.2794 0.9906)
			(end 0.2794 -0.1016)
			(stroke
				(width 0.1)
				(type default)
			)
			(layer "F.Fab")
		)
		(fp_line
			(start 0.2794 -0.1016)
			(end -0.2794 -0.1016)
			(stroke
				(width 0.1)
				(type default)
			)
			(layer "F.Fab")
		)
		(fp_line
			(start -0.2794 0.9906)
			(end 0.2794 0.9906)
			(stroke
				(width 0.1)
				(type default)
			)
			(layer "F.Fab")
		)
		(fp_line
			(start -0.2794 -0.1016)
			(end -0.2794 0.9906)
			(stroke
				(width 0.1)
				(type default)
			)
			(layer "F.Fab")
		)
		(pad "1" smd rect
			(at 0 0 180)
			(size 0.508 0.508)
			(layers "F.Cu" "F.Mask" "F.Paste")
			(net "CLK_322M_156M_CPU0_OSC_VRM_DP")
		)
		(pad "2" smd rect
			(at 0 0.889 180)
			(size 0.508 0.508)
			(layers "F.Cu" "F.Mask" "F.Paste")
			(net "CLK_156M_OSC_CPU0_HFI_DP")
		)
		(zone
			(layer "F.Cu")
			(hatch none 0.5)
			(connect_pads
				(clearance 0)
			)
			(min_thickness 0.25)
			(keepout
				(tracks not_allowed)
				(vias allowed)
				(pads allowed)
				(copperpour not_allowed)
				(footprints allowed)
			)
			(placement
				(enabled no)
				(sheetname "")
			)
			(fill
				(thermal_gap 0.5)
				(thermal_bridge_width 0.5)
				(island_removal_mode 0)
			)
			(polygon
				(pts
					(xy 319.1256 -28.680918) (xy 318.6176 -28.680918) (xy 318.6176 -28.299918) (xy 319.1256 -28.299918)
				)
			)
		)
		(zone
			(layer "F.Cu")
			(hatch none 0.5)
			(connect_pads
				(clearance 0)
			)
			(min_thickness 0.25)
			(keepout
				(tracks allowed)
				(vias not_allowed)
				(pads allowed)
				(copperpour not_allowed)
				(footprints allowed)
			)
			(placement
				(enabled no)
				(sheetname "")
			)
			(fill
				(thermal_gap 0.5)
				(thermal_bridge_width 0.5)
				(island_removal_mode 0)
			)
			(polygon
				(pts
					(xy 319.1256 -28.299918) (xy 318.6176 -28.299918) (xy 318.6176 -28.680918) (xy 319.1256 -28.680918)
				)
			)
		)
	)
)
